(kicad_pcb
	(version 20260206)
	(generator "pcbnew")
	(generator_version "10.0")
	(general
		(thickness 1.6)
		(legacy_teardrops no)
	)
	(paper "A4")
	(title_block
		(title "Bryce Canyon_F.DPB_16315-1-OCP.brd")
		(comment 1 "Bryce Canyon / footprints 1184-1190 of 2223")
	)
	(layers
		(0 "F.Cu" signal "TOP")
		(4 "In1.Cu" signal "L2GND")
		(6 "In2.Cu" signal "L3")
		(8 "In3.Cu" signal "L4GND")
		(10 "In4.Cu" signal "L5")
		(12 "In5.Cu" signal "L6VCC")
		(14 "In6.Cu" signal "L7VCC")
		(16 "In7.Cu" signal "L8")
		(18 "In8.Cu" signal "L9GND")
		(20 "In9.Cu" signal "L10")
		(22 "In10.Cu" signal "L11GND")
		(2 "B.Cu" signal "BOTTOM")
		(9 "F.Adhes" user "F.Adhesive")
		(11 "B.Adhes" user "B.Adhesive")
		(13 "F.Paste" user "Package Geometry/Pastemask Top")
		(15 "B.Paste" user "Package Geometry/Pastemask Bottom")
		(5 "F.SilkS" user "Ref Des/Silkscreen Top")
		(7 "B.SilkS" user "Ref Des/Silkscreen Bottom")
		(1 "F.Mask" user "Board Geometry/Soldermask Top")
		(3 "B.Mask" user "Board Geometry/Soldermask Bottom")
		(17 "Dwgs.User" user "User.Drawings")
		(19 "Cmts.User" user "User.Comments")
		(21 "Eco1.User" user "User.Eco1")
		(23 "Eco2.User" user "User.Eco2")
		(25 "Edge.Cuts" user "Board Geometry/Outline")
		(27 "Margin" user)
		(31 "F.CrtYd" user "Package Geometry/Place Bound Top")
		(29 "B.CrtYd" user "Package Geometry/Place Bound Bottom")
		(35 "F.Fab" user "Ref Des/Assembly Top")
		(33 "B.Fab" user "Ref Des/Assembly Bottom")
	)
	(footprint ""
		(layer "F.Cu")
		(at 54.546246 -158.347918 -90)
		(property "Reference" "R437"
			(at 0 0 270)
			(layer "F.SilkS")
			(hide yes)
			(effects
				(font
					(size 1.27 1.27)
				)
			)
		)
		(property "Value" "1KR2F-3-GP"
			(at 0.064008 -3.993896 270)
			(unlocked yes)
			(layer "F.Fab")
			(hide yes)
			(effects
				(font
					(size 1.016 1.016)
					(thickness 0.1524)
				)
			)
		)
		(property "Device Type" "R402H16"
			(at 0.064008 -5.517896 270)
			(unlocked yes)
			(layer "F.Fab")
			(hide yes)
			(effects
				(font
					(size 1.016 1.016)
					(thickness 0.1524)
				)
			)
		)
		(duplicate_pad_numbers_are_jumpers no)
		(fp_line
			(start -0.508 -0.9398)
			(end -0.508 0.9398)
			(stroke
				(width 0.1524)
				(type default)
			)
			(layer "F.SilkS")
		)
		(fp_line
			(start 0.508 -0.9398)
			(end -0.508 -0.9398)
			(stroke
				(width 0.1524)
				(type default)
			)
			(layer "F.SilkS")
		)
		(fp_rect
			(start -0.508 0.9398)
			(end 0.508 -0.9398)
			(stroke
				(width 0)
				(type default)
			)
			(fill no)
			(layer "F.CrtYd")
		)
		(fp_rect
			(start -0.508 0.9398)
			(end 0.508 -0.9398)
			(stroke
				(width 0)
				(type default)
			)
			(fill no)
			(layer "F.Fab")
		)
		(pad "1" smd custom
			(at 0 -0.4445 270)
			(size 0.1397 0.1397)
			(layers "F.Cu" "F.Mask" "F.Paste")
			(net "P3V3_STBY_A")
			(options
				(clearance outline)
				(anchor circle)
			)
			(primitives
				(gr_poly
					(pts
						(arc
							(start -0.1778 -0.2794)
							(mid -0.249642 -0.249642)
							(end -0.2794 -0.1778)
						)
						(arc
							(start -0.2794 0.1778)
							(mid -0.249642 0.249642)
							(end -0.1778 0.2794)
						)
						(arc
							(start 0.1778 0.2794)
							(mid 0.249642 0.249642)
							(end 0.2794 0.1778)
						)
						(arc
							(start 0.2794 -0.1778)
							(mid 0.249642 -0.249642)
							(end 0.1778 -0.2794)
						)
					)
					(width 0)
					(fill yes)
				)
			)
		)
		(pad "2" smd custom
			(at 0 0.4445 270)
			(size 0.1397 0.1397)
			(layers "F.Cu" "F.Mask" "F.Paste")
			(net "SW_PWR_R_HDD13")
			(options
				(clearance outline)
				(anchor circle)
			)
			(primitives
				(gr_poly
					(pts
						(arc
							(start -0.1778 -0.2794)
							(mid -0.249642 -0.249642)
							(end -0.2794 -0.1778)
						)
						(arc
							(start -0.2794 0.1778)
							(mid -0.249642 0.249642)
							(end -0.1778 0.2794)
						)
						(arc
							(start 0.1778 0.2794)
							(mid 0.249642 0.249642)
							(end 0.2794 0.1778)
						)
						(arc
							(start 0.2794 -0.1778)
							(mid 0.249642 -0.249642)
							(end 0.1778 -0.2794)
						)
					)
					(width 0)
					(fill yes)
				)
			)
		)
	)
	(footprint ""
		(layer "F.Cu")
		(at 33.325054 -322.799964)
		(property "Reference" ""
			(at 0 0 0)
			(layer "F.SilkS")
			(hide yes)
			(effects
				(font
					(size 1.27 1.27)
				)
			)
		)
		(property "Value" "*"
			(at -8.398764 -8.057642 0)
			(unlocked yes)
			(layer "F.Fab")
			(hide yes)
			(effects
				(font
					(size 1.016 1.016)
					(thickness 0.1524)
				)
			)
		)
		(duplicate_pad_numbers_are_jumpers no)
		(fp_poly
			(pts
				(arc
					(start 7.3152 0)
					(mid 0 7.3152)
					(end -7.3152 0)
				)
				(arc
					(start -7.3152 -5.9944)
					(mid 0 -13.3096)
					(end 7.3152 -5.9944)
				)
			)
			(stroke
				(width 0)
				(type default)
			)
			(fill no)
			(layer "B.CrtYd")
		)
		(fp_poly
			(pts
				(arc
					(start 7.3152 0)
					(mid 0 7.3152)
					(end -7.3152 0)
				)
				(arc
					(start -7.3152 -5.9944)
					(mid 0 -13.3096)
					(end 7.3152 -5.9944)
				)
			)
			(stroke
				(width 0)
				(type default)
			)
			(fill no)
			(layer "F.CrtYd")
		)
		(fp_poly
			(pts
				(arc
					(start 7.3152 0)
					(mid 0 7.3152)
					(end -7.3152 0)
				)
				(arc
					(start -7.3152 -5.9944)
					(mid 0 -13.3096)
					(end 7.3152 -5.9944)
				)
			)
			(stroke
				(width 0)
				(type default)
			)
			(fill no)
			(layer "B.Fab")
		)
		(fp_poly
			(pts
				(arc
					(start 7.3152 0)
					(mid 0 7.3152)
					(end -7.3152 0)
				)
				(arc
					(start -7.3152 -5.9944)
					(mid 0 -13.3096)
					(end 7.3152 -5.9944)
				)
			)
			(stroke
				(width 0)
				(type default)
			)
			(fill no)
			(layer "F.Fab")
		)
		(pad "1" thru_hole oval
			(at 0 0)
			(size 14.0208 20.0152)
			(drill 0.0254
				(offset 0 -2.9972)
			)
			(layers "*.Cu" "*.Mask")
			(remove_unused_layers no)
			(net "Net_39")
			(clearance -1.002284)
			(thermal_gap 0.1524)
			(padstack
				(mode front_inner_back)
				(layer "Inner"
					(shape custom)
					(size 2.928012 2.928012)
					(options
						(anchor circle)
					)
					(primitives
						(gr_poly
							(pts
								(arc
									(start 4.571746 -2.084324)
									(mid 0.000333 7.430372)
									(end -4.571492 -2.084324)
								)
								(arc
									(start -4.571492 -2.084324)
									(mid -3.570296 -3.611977)
									(end -2.875026 -5.30098)
								)
								(arc
									(start -2.875026 -5.30098)
									(mid 0.000217 -7.43089)
									(end 2.87528 -5.30098)
								)
								(arc
									(start 2.87528 -5.30098)
									(mid 3.570511 -3.611956)
									(end 4.571746 -2.084324)
								)
							)
							(width 0)
							(fill yes)
						)
					)
					(clearance 0.1524)
				)
				(layer "B.Cu"
					(shape oval)
					(size 14.0208 20.0152)
					(offset 0 -2.9972)
					(clearance -1.002284)
				)
			)
		)
		(zone
			(layers "F.Cu" "B.Cu" "In1.Cu" "In2.Cu" "In3.Cu" "In4.Cu" "In5.Cu" "In6.Cu"
				"In7.Cu" "In8.Cu" "In9.Cu" "In10.Cu"
			)
			(hatch none 0.5)
			(connect_pads
				(clearance 0)
			)
			(min_thickness 0.25)
			(keepout
				(tracks not_allowed)
				(vias allowed)
				(pads allowed)
				(copperpour not_allowed)
				(footprints allowed)
			)
			(placement
				(enabled no)
				(sheetname "")
			)
			(fill
				(thermal_gap 0.5)
				(thermal_bridge_width 0.5)
				(island_removal_mode 0)
			)
			(polygon
				(pts
					(arc
						(start 26.314654 -328.794364)
						(mid 33.325054 -335.804764)
						(end 40.335454 -328.794364)
					)
					(arc
						(start 40.335454 -322.799964)
						(mid 33.325054 -315.789564)
						(end 26.314654 -322.799964)
					)
				)
			)
		)
	)
	(footprint ""
		(layer "F.Cu")
		(at 33.798002 -255.96215)
		(property "Reference" "R1205"
			(at 0 0 0)
			(layer "F.SilkS")
			(hide yes)
			(effects
				(font
					(size 1.27 1.27)
				)
			)
		)
		(property "Value" "49K9R2F-L-GP"
			(at 0.064008 -3.993896 0)
			(unlocked yes)
			(layer "F.Fab")
			(hide yes)
			(effects
				(font
					(size 1.016 1.016)
					(thickness 0.1524)
				)
			)
		)
		(property "Device Type" "R402H16"
			(at 0.064008 -5.517896 0)
			(unlocked yes)
			(layer "F.Fab")
			(hide yes)
			(effects
				(font
					(size 1.016 1.016)
					(thickness 0.1524)
				)
			)
		)
		(duplicate_pad_numbers_are_jumpers no)
		(fp_line
			(start -0.508 -0.9398)
			(end -0.508 0.9398)
			(stroke
				(width 0.1524)
				(type default)
			)
			(layer "F.SilkS")
		)
		(fp_line
			(start 0.508 -0.9398)
			(end -0.508 -0.9398)
			(stroke
				(width 0.1524)
				(type default)
			)
			(layer "F.SilkS")
		)
		(fp_rect
			(start -0.508 0.9398)
			(end 0.508 -0.9398)
			(stroke
				(width 0)
				(type default)
			)
			(fill no)
			(layer "F.CrtYd")
		)
		(fp_rect
			(start -0.508 0.9398)
			(end 0.508 -0.9398)
			(stroke
				(width 0)
				(type default)
			)
			(fill no)
			(layer "F.Fab")
		)
		(pad "1" smd custom
			(at 0 -0.4445)
			(size 0.1397 0.1397)
			(layers "F.Cu" "F.Mask" "F.Paste")
			(net "P12V_A")
			(options
				(clearance outline)
				(anchor circle)
			)
			(primitives
				(gr_poly
					(pts
						(arc
							(start -0.1778 -0.2794)
							(mid -0.249642 -0.249642)
							(end -0.2794 -0.1778)
						)
						(arc
							(start -0.2794 0.1778)
							(mid -0.249642 0.249642)
							(end -0.1778 0.2794)
						)
						(arc
							(start 0.1778 0.2794)
							(mid 0.249642 0.249642)
							(end 0.2794 0.1778)
						)
						(arc
							(start 0.2794 -0.1778)
							(mid 0.249642 -0.249642)
							(end 0.1778 -0.2794)
						)
					)
					(width 0)
					(fill yes)
				)
			)
		)
		(pad "2" smd custom
			(at 0 0.4445)
			(size 0.1397 0.1397)
			(layers "F.Cu" "F.Mask" "F.Paste")
			(net "P5V_A_EN_R")
			(options
				(clearance outline)
				(anchor circle)
			)
			(primitives
				(gr_poly
					(pts
						(arc
							(start -0.1778 -0.2794)
							(mid -0.249642 -0.249642)
							(end -0.2794 -0.1778)
						)
						(arc
							(start -0.2794 0.1778)
							(mid -0.249642 0.249642)
							(end -0.1778 0.2794)
						)
						(arc
							(start 0.1778 0.2794)
							(mid 0.249642 0.249642)
							(end 0.2794 0.1778)
						)
						(arc
							(start 0.2794 -0.1778)
							(mid 0.249642 -0.249642)
							(end 0.1778 -0.2794)
						)
					)
					(width 0)
					(fill yes)
				)
			)
		)
	)
	(footprint ""
		(layer "F.Cu")
		(at 246.253 -388.4168 -90)
		(property "Reference" "R1155"
			(at 0 0 270)
			(layer "F.SilkS")
			(hide yes)
			(effects
				(font
					(size 1.27 1.27)
				)
			)
		)
		(property "Value" "10R2F-L-GP"
			(at 0.064008 -3.993896 270)
			(unlocked yes)
			(layer "F.Fab")
			(hide yes)
			(effects
				(font
					(size 1.016 1.016)
					(thickness 0.1524)
				)
			)
		)
		(property "Device Type" "R402H14"
			(at 0.064008 -5.517896 270)
			(unlocked yes)
			(layer "F.Fab")
			(hide yes)
			(effects
				(font
					(size 1.016 1.016)
					(thickness 0.1524)
				)
			)
		)
		(duplicate_pad_numbers_are_jumpers no)
		(fp_line
			(start -0.508 -0.9398)
			(end -0.508 0.9398)
			(stroke
				(width 0.1524)
				(type default)
			)
			(layer "F.SilkS")
		)
		(fp_line
			(start 0.508 -0.9398)
			(end -0.508 -0.9398)
			(stroke
				(width 0.1524)
				(type default)
			)
			(layer "F.SilkS")
		)
		(fp_rect
			(start -0.508 0.9398)
			(end 0.508 -0.9398)
			(stroke
				(width 0)
				(type default)
			)
			(fill no)
			(layer "F.CrtYd")
		)
		(fp_rect
			(start -0.508 0.9398)
			(end 0.508 -0.9398)
			(stroke
				(width 0)
				(type default)
			)
			(fill no)
			(layer "F.Fab")
		)
		(pad "1" smd custom
			(at 0 -0.4445 270)
			(size 0.1397 0.1397)
			(layers "F.Cu" "F.Mask" "F.Paste")
			(net "MB3_CM_SENSE_R1_P")
			(options
				(clearance outline)
				(anchor circle)
			)
			(primitives
				(gr_poly
					(pts
						(arc
							(start -0.1778 -0.2794)
							(mid -0.249642 -0.249642)
							(end -0.2794 -0.1778)
						)
						(arc
							(start -0.2794 0.1778)
							(mid -0.249642 0.249642)
							(end -0.1778 0.2794)
						)
						(arc
							(start 0.1778 0.2794)
							(mid 0.249642 0.249642)
							(end 0.2794 0.1778)
						)
						(arc
							(start 0.2794 -0.1778)
							(mid 0.249642 -0.249642)
							(end 0.1778 -0.2794)
						)
					)
					(width 0)
					(fill yes)
				)
			)
		)
		(pad "2" smd custom
			(at 0 0.4445 270)
			(size 0.1397 0.1397)
			(layers "F.Cu" "F.Mask" "F.Paste")
			(net "MB3_HS_SENSE_P")
			(options
				(clearance outline)
				(anchor circle)
			)
			(primitives
				(gr_poly
					(pts
						(arc
							(start -0.1778 -0.2794)
							(mid -0.249642 -0.249642)
							(end -0.2794 -0.1778)
						)
						(arc
							(start -0.2794 0.1778)
							(mid -0.249642 0.249642)
							(end -0.1778 0.2794)
						)
						(arc
							(start 0.1778 0.2794)
							(mid 0.249642 0.249642)
							(end 0.2794 0.1778)
						)
						(arc
							(start 0.2794 -0.1778)
							(mid 0.249642 -0.249642)
							(end 0.1778 -0.2794)
						)
					)
					(width 0)
					(fill yes)
				)
			)
		)
	)
	(footprint ""
		(layer "F.Cu")
		(at 223.887792 -344.628978 180)
		(property "Reference" "R28"
			(at 0 0 180)
			(layer "F.SilkS")
			(hide yes)
			(effects
				(font
					(size 1.27 1.27)
				)
			)
		)
		(property "Value" "4K7R2F-GP"
			(at 0.064008 -3.993896 180)
			(unlocked yes)
			(layer "F.Fab")
			(hide yes)
			(effects
				(font
					(size 1.016 1.016)
					(thickness 0.1524)
				)
			)
		)
		(property "Device Type" "R402H16"
			(at 0.064008 -5.517896 180)
			(unlocked yes)
			(layer "F.Fab")
			(hide yes)
			(effects
				(font
					(size 1.016 1.016)
					(thickness 0.1524)
				)
			)
		)
		(duplicate_pad_numbers_are_jumpers no)
		(fp_line
			(start 0.508 -0.9398)
			(end -0.508 -0.9398)
			(stroke
				(width 0.1524)
				(type default)
			)
			(layer "F.SilkS")
		)
		(fp_line
			(start -0.508 -0.9398)
			(end -0.508 0.9398)
			(stroke
				(width 0.1524)
				(type default)
			)
			(layer "F.SilkS")
		)
		(fp_rect
			(start -0.508 0.9398)
			(end 0.508 -0.9398)
			(stroke
				(width 0)
				(type default)
			)
			(fill no)
			(layer "F.CrtYd")
		)
		(fp_rect
			(start -0.508 0.9398)
			(end 0.508 -0.9398)
			(stroke
				(width 0)
				(type default)
			)
			(fill no)
			(layer "F.Fab")
		)
		(pad "1" smd custom
			(at 0 -0.4445 180)
			(size 0.1397 0.1397)
			(layers "F.Cu" "F.Mask" "F.Paste")
			(net "VOL_SEN_ADDR0")
			(options
				(clearance outline)
				(anchor circle)
			)
			(primitives
				(gr_poly
					(pts
						(arc
							(start -0.1778 -0.2794)
							(mid -0.249642 -0.249642)
							(end -0.2794 -0.1778)
						)
						(arc
							(start -0.2794 0.1778)
							(mid -0.249642 0.249642)
							(end -0.1778 0.2794)
						)
						(arc
							(start 0.1778 0.2794)
							(mid 0.249642 0.249642)
							(end 0.2794 0.1778)
						)
						(arc
							(start 0.2794 -0.1778)
							(mid 0.249642 -0.249642)
							(end 0.1778 -0.2794)
						)
					)
					(width 0)
					(fill yes)
				)
			)
		)
		(pad "2" smd custom
			(at 0 0.4445 180)
			(size 0.1397 0.1397)
			(layers "F.Cu" "F.Mask" "F.Paste")
			(net "GND")
			(options
				(clearance outline)
				(anchor circle)
			)
			(primitives
				(gr_poly
					(pts
						(arc
							(start -0.1778 -0.2794)
							(mid -0.249642 -0.249642)
							(end -0.2794 -0.1778)
						)
						(arc
							(start -0.2794 0.1778)
							(mid -0.249642 0.249642)
							(end -0.1778 0.2794)
						)
						(arc
							(start 0.1778 0.2794)
							(mid 0.249642 0.249642)
							(end 0.2794 0.1778)
						)
						(arc
							(start 0.2794 -0.1778)
							(mid 0.249642 -0.249642)
							(end 0.1778 -0.2794)
						)
					)
					(width 0)
					(fill yes)
				)
			)
		)
	)
	(footprint ""
		(layer "F.Cu")
		(at 82.006948 -179.683918 90)
		(property "Reference" "R453"
			(at 0 0 90)
			(layer "F.SilkS")
			(hide yes)
			(effects
				(font
					(size 1.27 1.27)
				)
			)
		)
		(property "Value" "2R6F-GP"
			(at -0.0508 -4.8514 90)
			(unlocked yes)
			(layer "F.Fab")
			(hide yes)
			(effects
				(font
					(size 1.016 1.016)
					(thickness 0.1524)
				)
			)
		)
		(property "Device Type" "R1206H26"
			(at 0 -6.3754 90)
			(unlocked yes)
			(layer "F.Fab")
			(hide yes)
			(effects
				(font
					(size 1.016 1.016)
					(thickness 0.1524)
				)
			)
		)
		(duplicate_pad_numbers_are_jumpers no)
		(fp_line
			(start 1.016 -2.2352)
			(end 1.016 2.2352)
			(stroke
				(width 0.1524)
				(type default)
			)
			(layer "F.SilkS")
		)
		(fp_line
			(start -1.016 -2.2352)
			(end 1.016 -2.2352)
			(stroke
				(width 0.1524)
				(type default)
			)
			(layer "F.SilkS")
		)
		(fp_line
			(start 1.016 2.2352)
			(end -1.016 2.2352)
			(stroke
				(width 0.1524)
				(type default)
			)
			(layer "F.SilkS")
		)
		(fp_line
			(start -1.016 2.2352)
			(end -1.016 -2.2352)
			(stroke
				(width 0.1524)
				(type default)
			)
			(layer "F.SilkS")
		)
		(fp_rect
			(start -1.0922 2.3114)
			(end 1.0922 -2.3114)
			(stroke
				(width 0)
				(type default)
			)
			(fill no)
			(layer "F.CrtYd")
		)
		(fp_poly
			(pts
				(xy -1.0922 -2.3114) (xy 1.0922 -2.3114) (xy 1.0922 2.3114) (xy -1.0922 2.3114)
			)
			(stroke
				(width 0)
				(type default)
			)
			(fill no)
			(layer "F.Fab")
		)
		(pad "1" smd rect
			(at 0 -1.397 90)
			(size 1.651 1.27)
			(layers "F.Cu" "F.Mask" "F.Paste")
			(net "P12V_HDD14")
		)
		(pad "2" smd rect
			(at 0 1.397 90)
			(size 1.651 1.27)
			(layers "F.Cu" "F.Mask" "F.Paste")
			(net "12V_PRE_14")
		)
	)
	(footprint ""
		(layer "F.Cu")
		(at 440.694826 -127.254)
		(property "Reference" "R339"
			(at 0 0 0)
			(layer "F.SilkS")
			(hide yes)
			(effects
				(font
					(size 1.27 1.27)
				)
			)
		)
		(property "Value" "130R3F-GP"
			(at -0.0254 -2.5146 0)
			(unlocked yes)
			(layer "F.Fab")
			(hide yes)
			(effects
				(font
					(size 1.016 1.016)
					(thickness 0.1524)
				)
			)
		)
		(property "Device Type" "R603H22"
			(at -0.0254 -4.0386 0)
			(unlocked yes)
			(layer "F.Fab")
			(hide yes)
			(effects
				(font
					(size 1.016 1.016)
					(thickness 0.1524)
				)
			)
		)
		(duplicate_pad_numbers_are_jumpers no)
		(fp_line
			(start -0.4826 0)
			(end -0.2032 0)
			(stroke
				(width 0.2032)
				(type default)
			)
			(layer "F.SilkS")
		)
		(fp_line
			(start 0.2032 0)
			(end 0.4826 0)
			(stroke
				(width 0.2032)
				(type default)
			)
			(layer "F.SilkS")
		)
		(fp_rect
			(start -0.5842 1.3335)
			(end 0.5842 -1.3335)
			(stroke
				(width 0)
				(type default)
			)
			(fill no)
			(layer "F.CrtYd")
		)
		(fp_rect
			(start -0.5842 1.3335)
			(end 0.5842 -1.3335)
			(stroke
				(width 0)
				(type default)
			)
			(fill no)
			(layer "F.Fab")
		)
		(pad "1" smd custom
			(at 0 -0.762)
			(size 0.2159 0.2159)
			(layers "F.Cu" "F.Mask" "F.Paste")
			(net "P5V_A_4")
			(options
				(clearance outline)
				(anchor circle)
			)
			(primitives
				(gr_poly
					(pts
						(arc
							(start -0.3302 -0.4318)
							(mid -0.402042 -0.402042)
							(end -0.4318 -0.3302)
						)
						(arc
							(start -0.4318 0.3302)
							(mid -0.402042 0.402042)
							(end -0.3302 0.4318)
						)
						(arc
							(start 0.3302 0.4318)
							(mid 0.402042 0.402042)
							(end 0.4318 0.3302)
						)
						(arc
							(start 0.4318 -0.3302)
							(mid 0.402042 -0.402042)
							(end 0.3302 -0.4318)
						)
					)
					(width 0)
					(fill yes)
				)
			)
		)
		(pad "2" smd custom
			(at 0 0.762)
			(size 0.2159 0.2159)
			(layers "F.Cu" "F.Mask" "F.Paste")
			(net "FLT_HDD22")
			(options
				(clearance outline)
				(anchor circle)
			)
			(primitives
				(gr_poly
					(pts
						(arc
							(start -0.3302 -0.4318)
							(mid -0.402042 -0.402042)
							(end -0.4318 -0.3302)
						)
						(arc
							(start -0.4318 0.3302)
							(mid -0.402042 0.402042)
							(end -0.3302 0.4318)
						)
						(arc
							(start 0.3302 0.4318)
							(mid 0.402042 0.402042)
							(end 0.4318 0.3302)
						)
						(arc
							(start 0.4318 -0.3302)
							(mid 0.402042 -0.402042)
							(end 0.3302 -0.4318)
						)
					)
					(width 0)
					(fill yes)
				)
			)
		)
	)
)
